(kicad_pcb
	(version 20221018)
	(generator pcbnew)
	(general
    (thickness 1.7403)
  )
	(paper "A4")
	(title_block
    (title "Data Center RDIMM DDR4 Tester")
    (date "2024-09-30")
    (rev "1.2.4")
		(comment 9 "footprints 47-56 of 690")
	)
	(layers
    (0 "F.Cu" signal)
    (1 "In1.Cu" power)
    (2 "In2.Cu" signal)
    (3 "In3.Cu" power)
    (4 "In4.Cu" power)
    (5 "In5.Cu" signal)
    (6 "In6.Cu" power)
    (7 "In7.Cu" signal)
    (8 "In8.Cu" power)
    (9 "In9.Cu" signal)
    (10 "In10.Cu" power)
    (31 "B.Cu" signal)
    (32 "B.Adhes" user "B.Adhesive")
    (33 "F.Adhes" user "F.Adhesive")
    (34 "B.Paste" user)
    (35 "F.Paste" user)
    (36 "B.SilkS" user "B.Silkscreen")
    (37 "F.SilkS" user "F.Silkscreen")
    (38 "B.Mask" user)
    (39 "F.Mask" user)
    (40 "Dwgs.User" user "User.Drawings")
    (41 "Cmts.User" user "User.Comments")
    (42 "Eco1.User" user "User.Eco1")
    (43 "Eco2.User" user "User.Eco2")
    (44 "Edge.Cuts" user)
    (45 "Margin" user)
    (46 "B.CrtYd" user "B.Courtyard")
    (47 "F.CrtYd" user "F.Courtyard")
    (48 "B.Fab" user)
    (49 "F.Fab" user)
  )
	(footprint "data-center-rdimm-ddr4-tester-footprints:R_0402_1005Metric" (layer "F.Cu")
    (at 148.056328 111.982157)
    (descr "Resistor SMD 0402")
    (tags "resistor SMD 0402")
    (property "Author" "Antmicro")
    (property "License" "Apache-2.0")
    (property "MPN" "CR0402-FX-22R0GLF")
    (property "Manufacturer" "Bourns")
    (property "Sheetfile" "interfaces.kicad_sch")
    (property "Sheetname" "Interfaces")
    (property "Tolerance" "1%")
    (property "Val" "22R")
    (property "ki_description" "22R resistor in 0402 package with 1% tolerance")
    (attr smd)
    (fp_text reference "R19" (at 0.863672 0.277843) (layer "F.SilkS")
        (effects (font (size 0.7 0.7) (thickness 0.15)) (justify left bottom))
    )
    (fp_text value "R_22R_0402" (at 0 1.4) (layer "F.Fab") hide
        (effects (font (size 0.7 0.7) (thickness 0.15)) (justify left bottom))
    )
    (fp_text user "Author: Antmicro" (at -0.95 4.169) (layer "F.Fab") hide
        (effects (font (size 0.7 0.7) (thickness 0.15)) (justify left bottom))
    )
    (fp_text user "License: Apache-2.0" (at -0.95 5.169) (layer "F.Fab") hide
        (effects (font (size 0.7 0.7) (thickness 0.15)) (justify left bottom))
    )
    (fp_text user "${REFERENCE}" (at -0.95 3.168) (layer "F.Fab") hide
        (effects (font (size 0.7 0.7) (thickness 0.15)) (justify left bottom))
    )
    (fp_rect (start -0.93 -0.47) (end 0.93 0.47)
      (stroke (width 0.05) (type solid)) (fill none) (layer "F.CrtYd"))
    (fp_rect (start -0.5 -0.25) (end 0.5 0.25)
      (stroke (width 0.15) (type solid)) (fill none) (layer "F.Fab"))
    (pad "1" smd roundrect (at -0.485 0) (size 0.59 0.64) (layers "F.Cu" "F.Paste" "F.Mask") (roundrect_rratio 0.25)
      (net 594 "Net-(U7-ADBUS1)") (pintype "passive"))
    (pad "2" smd roundrect (at 0.485 0) (size 0.59 0.64) (layers "F.Cu" "F.Paste" "F.Mask") (roundrect_rratio 0.25)
      (net 14 "TDI_JTAG") (pintype "passive"))
  )
	(footprint "data-center-rdimm-ddr4-tester-footprints:R_0402_1005Metric" (layer "F.Cu")
    (at 148.036328 113.122157)
    (descr "Resistor SMD 0402")
    (tags "resistor SMD 0402")
    (property "Author" "Antmicro")
    (property "License" "Apache-2.0")
    (property "MPN" "CR0402-FX-22R0GLF")
    (property "Manufacturer" "Bourns")
    (property "Sheetfile" "interfaces.kicad_sch")
    (property "Sheetname" "Interfaces")
    (property "Tolerance" "1%")
    (property "Val" "22R")
    (property "ki_description" "22R resistor in 0402 package with 1% tolerance")
    (attr smd)
    (fp_text reference "R18" (at 0.863672 0.137843) (layer "F.SilkS")
        (effects (font (size 0.7 0.7) (thickness 0.15)) (justify left bottom))
    )
    (fp_text value "R_22R_0402" (at 0 1.4) (layer "F.Fab") hide
        (effects (font (size 0.7 0.7) (thickness 0.15)) (justify left bottom))
    )
    (fp_text user "${REFERENCE}" (at -0.95 3.168) (layer "F.Fab") hide
        (effects (font (size 0.7 0.7) (thickness 0.15)) (justify left bottom))
    )
    (fp_text user "License: Apache-2.0" (at -0.95 5.169) (layer "F.Fab") hide
        (effects (font (size 0.7 0.7) (thickness 0.15)) (justify left bottom))
    )
    (fp_text user "Author: Antmicro" (at -0.95 4.169) (layer "F.Fab") hide
        (effects (font (size 0.7 0.7) (thickness 0.15)) (justify left bottom))
    )
    (fp_rect (start -0.93 -0.47) (end 0.93 0.47)
      (stroke (width 0.05) (type solid)) (fill none) (layer "F.CrtYd"))
    (fp_rect (start -0.5 -0.25) (end 0.5 0.25)
      (stroke (width 0.15) (type solid)) (fill none) (layer "F.Fab"))
    (pad "1" smd roundrect (at -0.485 0) (size 0.59 0.64) (layers "F.Cu" "F.Paste" "F.Mask") (roundrect_rratio 0.25)
      (net 593 "Net-(U7-ADBUS0)") (pintype "passive"))
    (pad "2" smd roundrect (at 0.485 0) (size 0.59 0.64) (layers "F.Cu" "F.Paste" "F.Mask") (roundrect_rratio 0.25)
      (net 12 "TCK_JTAG") (pintype "passive"))
  )
	(footprint "data-center-rdimm-ddr4-tester-footprints:C_0402_1005Metric" (layer "F.Cu")
    (at 133.946328 107.407157 180)
    (descr "Capacitor SMD 0402")
    (tags "capacitor SMD 0402")
    (property "Author" "Antmicro")
    (property "Dielectric" "X5R")
    (property "License" "Apache-2.0")
    (property "MPN" "GRM155R61H104KE14D")
    (property "Manufacturer" "Murata")
    (property "Sheetfile" "interfaces.kicad_sch")
    (property "Sheetname" "Interfaces")
    (property "Val" "100n")
    (property "Voltage" "50V")
    (property "ki_description" " ")
    (attr smd)
    (fp_text reference "C186" (at 3.766328 -0.322843 180) (layer "F.SilkS")
        (effects (font (size 0.7 0.7) (thickness 0.15)) (justify left bottom))
    )
    (fp_text value "C_100n_0402" (at 0 1.4 180) (layer "F.Fab") hide
        (effects (font (size 0.7 0.7) (thickness 0.15)) (justify left bottom))
    )
    (fp_text user "${REFERENCE}" (at -0.932 3.168 180) (layer "F.Fab") hide
        (effects (font (size 0.7 0.7) (thickness 0.15)) (justify left bottom))
    )
    (fp_text user "License: Apache-2.0" (at -0.932 5.17 180) (layer "F.Fab") hide
        (effects (font (size 0.7 0.7) (thickness 0.15)) (justify left bottom))
    )
    (fp_text user "Author: Antmicro" (at -0.932 4.17 180) (layer "F.Fab") hide
        (effects (font (size 0.7 0.7) (thickness 0.15)) (justify left bottom))
    )
    (fp_rect (start -0.94 -0.47) (end 0.94 0.47)
      (stroke (width 0.05) (type solid)) (fill none) (layer "F.CrtYd"))
    (fp_rect (start -0.499 -0.249) (end 0.499 0.249)
      (stroke (width 0.15) (type solid)) (fill none) (layer "F.Fab"))
    (pad "1" smd roundrect (at -0.484 0 180) (size 0.59 0.64) (layers "F.Cu" "F.Paste" "F.Mask") (roundrect_rratio 0.25)
      (net 143 "3V3_SYS") (pintype "passive"))
    (pad "2" smd roundrect (at 0.484 0 180) (size 0.59 0.64) (layers "F.Cu" "F.Paste" "F.Mask") (roundrect_rratio 0.25)
      (net 9 "GND") (pintype "passive"))
  )
	(footprint "data-center-rdimm-ddr4-tester-footprints:C_0402_1005Metric" (layer "F.Cu")
    (at 133 116 -90)
    (descr "Capacitor SMD 0402")
    (tags "capacitor SMD 0402")
    (property "Author" "Antmicro")
    (property "Dielectric" "")
    (property "License" "Apache-2.0")
    (property "MPN" "MC0402N180J500CT")
    (property "Manufacturer" "Multicomp")
    (property "Sheetfile" "interfaces.kicad_sch")
    (property "Sheetname" "Interfaces")
    (property "Val" "18p")
    (property "Voltage" "")
    (property "ki_description" " ")
    (attr smd)
    (fp_text reference "C190" (at -0.717157 -0.388672 -90) (layer "F.SilkS")
        (effects (font (size 0.7 0.7) (thickness 0.15)) (justify left bottom))
    )
    (fp_text value "C_18p_0402" (at 0 1.4 -90) (layer "F.Fab") hide
        (effects (font (size 0.7 0.7) (thickness 0.15)) (justify left bottom))
    )
    (fp_text user "${REFERENCE}" (at -0.932 3.168 -90) (layer "F.Fab") hide
        (effects (font (size 0.7 0.7) (thickness 0.15)) (justify left bottom))
    )
    (fp_text user "License: Apache-2.0" (at -0.932 5.17 -90) (layer "F.Fab") hide
        (effects (font (size 0.7 0.7) (thickness 0.15)) (justify left bottom))
    )
    (fp_text user "Author: Antmicro" (at -0.932 4.17 -90) (layer "F.Fab") hide
        (effects (font (size 0.7 0.7) (thickness 0.15)) (justify left bottom))
    )
    (fp_rect (start -0.94 -0.47) (end 0.94 0.47)
      (stroke (width 0.05) (type solid)) (fill none) (layer "F.CrtYd"))
    (fp_rect (start -0.499 -0.249) (end 0.499 0.249)
      (stroke (width 0.15) (type solid)) (fill none) (layer "F.Fab"))
    (pad "1" smd roundrect (at -0.484 0 270) (size 0.59 0.64) (layers "F.Cu" "F.Paste" "F.Mask") (roundrect_rratio 0.25)
      (net 80 "Net-(U7-OSCI)") (pintype "passive"))
    (pad "2" smd roundrect (at 0.484 0 270) (size 0.59 0.64) (layers "F.Cu" "F.Paste" "F.Mask") (roundrect_rratio 0.25)
      (net 9 "GND") (pintype "passive"))
  )
	(footprint "data-center-rdimm-ddr4-tester-footprints:C_0402_1005Metric" (layer "F.Cu")
    (at 148.035 108.8)
    (descr "Capacitor SMD 0402")
    (tags "capacitor SMD 0402")
    (property "Author" "Antmicro")
    (property "Dielectric" "X5R")
    (property "License" "Apache-2.0")
    (property "MPN" "GRM155R61H104KE14D")
    (property "Manufacturer" "Murata")
    (property "Sheetfile" "interfaces.kicad_sch")
    (property "Sheetname" "Interfaces")
    (property "Val" "100n")
    (property "Voltage" "50V")
    (property "ki_description" " ")
    (attr smd)
    (fp_text reference "C191" (at 0.864672 0.367843) (layer "F.SilkS")
        (effects (font (size 0.7 0.7) (thickness 0.15)) (justify left bottom))
    )
    (fp_text value "C_100n_0402" (at 0 1.4) (layer "F.Fab") hide
        (effects (font (size 0.7 0.7) (thickness 0.15)) (justify left bottom))
    )
    (fp_text user "License: Apache-2.0" (at -0.932 5.17) (layer "F.Fab") hide
        (effects (font (size 0.7 0.7) (thickness 0.15)) (justify left bottom))
    )
    (fp_text user "Author: Antmicro" (at -0.932 4.17) (layer "F.Fab") hide
        (effects (font (size 0.7 0.7) (thickness 0.15)) (justify left bottom))
    )
    (fp_text user "${REFERENCE}" (at -0.932 3.168) (layer "F.Fab") hide
        (effects (font (size 0.7 0.7) (thickness 0.15)) (justify left bottom))
    )
    (fp_rect (start -0.94 -0.47) (end 0.94 0.47)
      (stroke (width 0.05) (type solid)) (fill none) (layer "F.CrtYd"))
    (fp_rect (start -0.499 -0.249) (end 0.499 0.249)
      (stroke (width 0.15) (type solid)) (fill none) (layer "F.Fab"))
    (pad "1" smd roundrect (at -0.484 0) (size 0.59 0.64) (layers "F.Cu" "F.Paste" "F.Mask") (roundrect_rratio 0.25)
      (net 143 "3V3_SYS") (pintype "passive"))
    (pad "2" smd roundrect (at 0.484 0) (size 0.59 0.64) (layers "F.Cu" "F.Paste" "F.Mask") (roundrect_rratio 0.25)
      (net 9 "GND") (pintype "passive"))
  )
	(footprint "data-center-rdimm-ddr4-tester-footprints:C_0402_1005Metric" (layer "F.Cu")
    (at 143.661328 100.212157 90)
    (descr "Capacitor SMD 0402")
    (tags "capacitor SMD 0402")
    (property "Author" "Antmicro")
    (property "Dielectric" "")
    (property "License" "Apache-2.0")
    (property "MPN" "GRM155R61A475MEAAD")
    (property "Manufacturer" "Murata")
    (property "Sheetfile" "interfaces.kicad_sch")
    (property "Sheetname" "Interfaces")
    (property "Val" "4u7")
    (property "Voltage" "")
    (property "ki_description" " ")
    (attr smd)
    (fp_text reference "C195" (at -1.117843 2.308672 90) (layer "F.SilkS")
        (effects (font (size 0.7 0.7) (thickness 0.15)) (justify left bottom))
    )
    (fp_text value "C_4u7_0402" (at 0 1.4 90) (layer "F.Fab") hide
        (effects (font (size 0.7 0.7) (thickness 0.15)) (justify left bottom))
    )
    (fp_text user "${REFERENCE}" (at -0.932 3.168 90) (layer "F.Fab") hide
        (effects (font (size 0.7 0.7) (thickness 0.15)) (justify left bottom))
    )
    (fp_text user "Author: Antmicro" (at -0.932 4.17 90) (layer "F.Fab") hide
        (effects (font (size 0.7 0.7) (thickness 0.15)) (justify left bottom))
    )
    (fp_text user "License: Apache-2.0" (at -0.932 5.17 90) (layer "F.Fab") hide
        (effects (font (size 0.7 0.7) (thickness 0.15)) (justify left bottom))
    )
    (fp_rect (start -0.94 -0.47) (end 0.94 0.47)
      (stroke (width 0.05) (type solid)) (fill none) (layer "F.CrtYd"))
    (fp_rect (start -0.499 -0.249) (end 0.499 0.249)
      (stroke (width 0.15) (type solid)) (fill none) (layer "F.Fab"))
    (pad "1" smd roundrect (at -0.484 0 90) (size 0.59 0.64) (layers "F.Cu" "F.Paste" "F.Mask") (roundrect_rratio 0.25)
      (net 145 "1V8_FT") (pintype "passive"))
    (pad "2" smd roundrect (at 0.484 0 90) (size 0.59 0.64) (layers "F.Cu" "F.Paste" "F.Mask") (roundrect_rratio 0.25)
      (net 9 "GND") (pintype "passive"))
  )
	(footprint "data-center-rdimm-ddr4-tester-footprints:FB_0603_1608Metric" (layer "F.Cu")
    (at 138.786328 117.497157 90)
    (property "Author" "Antmicro")
    (property "License" "Apache-2.0")
    (property "MPN" "BLM18AG601SN1D")
    (property "Manufacturer" "Murata")
    (property "Sheetfile" "interfaces.kicad_sch")
    (property "Sheetname" "Interfaces")
    (property "ki_description" "Ferrite Beads WE-TMSB Suppression 240Ohm 200mA ")
    (property "ki_keywords" " Multilayer Suppression Beads ")
    (attr smd)
    (fp_text reference "FB5" (at -2.302843 2.533672 90) (layer "F.SilkS")
        (effects (font (size 0.7 0.7) (thickness 0.15)) (justify left bottom))
    )
    (fp_text value "FB_600Z_0.5A_0603" (at 0 1.7 90) (layer "F.Fab") hide
        (effects (font (size 0.7 0.7) (thickness 0.15)) (justify left bottom))
    )
    (fp_text user "${REFERENCE}" (at -1.653 4.6 90) (layer "F.Fab") hide
        (effects (font (size 0.7 0.7) (thickness 0.15)) (justify left bottom))
    )
    (fp_text user "License: Apache-2.0" (at -1.653 5.9 90) (layer "F.Fab") hide
        (effects (font (size 0.7 0.7) (thickness 0.15)) (justify left bottom))
    )
    (fp_text user "Author: Antmicro" (at -1.653 3.162 90) (layer "F.Fab") hide
        (effects (font (size 0.7 0.7) (thickness 0.15)) (justify left bottom))
    )
    (fp_line (start -0.196 -0.408) (end 0.193 -0.408)
      (stroke (width 0.15) (type solid)) (layer "F.SilkS"))
    (fp_line (start -0.196 0.406) (end 0.193 0.406)
      (stroke (width 0.15) (type solid)) (layer "F.SilkS"))
    (fp_rect (start -1.42 -0.69) (end 1.42 0.69)
      (stroke (width 0.05) (type solid)) (fill none) (layer "F.CrtYd"))
    (fp_line (start -0.803 0.406) (end -0.803 -0.408)
      (stroke (width 0.15) (type solid)) (layer "F.Fab"))
    (fp_line (start 0.8 -0.408) (end -0.803 -0.408)
      (stroke (width 0.15) (type solid)) (layer "F.Fab"))
    (fp_line (start 0.8 -0.408) (end 0.8 0.406)
      (stroke (width 0.15) (type solid)) (layer "F.Fab"))
    (fp_line (start 0.8 0.406) (end -0.803 0.406)
      (stroke (width 0.15) (type solid)) (layer "F.Fab"))
    (pad "1" smd roundrect (at -0.891 0 90) (size 0.762 1.09) (layers "F.Cu" "F.Paste" "F.Mask") (roundrect_rratio 0.15)
      (net 143 "3V3_SYS") (pintype "passive"))
    (pad "2" smd roundrect (at 0.888 0 90) (size 0.762 1.09) (layers "F.Cu" "F.Paste" "F.Mask") (roundrect_rratio 0.15)
      (net 76 "Net-(U7-V_{PHY})") (pintype "passive"))
  )
	(footprint "data-center-rdimm-ddr4-tester-footprints:R_0402_1005Metric" (layer "F.Cu")
    (at 139.776328 114.627157 90)
    (descr "Resistor SMD 0402")
    (tags "resistor SMD 0402")
    (property "Author" "Antmicro")
    (property "License" "Apache-2.0")
    (property "MPN" "CR0402-FX-1202GLF")
    (property "Manufacturer" "Bourns")
    (property "Sheetfile" "interfaces.kicad_sch")
    (property "Sheetname" "Interfaces")
    (property "Tolerance" "1%")
    (property "Val" "12k")
    (property "ki_description" "12k resistor in 0402 package with 1% tolerance")
    (attr smd)
    (fp_text reference "R129" (at -1.102843 1.223672 90) (layer "F.SilkS")
        (effects (font (size 0.7 0.7) (thickness 0.15)) (justify left bottom))
    )
    (fp_text value "R_12k_0402" (at 0 1.4 90) (layer "F.Fab") hide
        (effects (font (size 0.7 0.7) (thickness 0.15)) (justify left bottom))
    )
    (fp_text user "License: Apache-2.0" (at -0.95 5.169 90) (layer "F.Fab") hide
        (effects (font (size 0.7 0.7) (thickness 0.15)) (justify left bottom))
    )
    (fp_text user "${REFERENCE}" (at -0.95 3.168 90) (layer "F.Fab") hide
        (effects (font (size 0.7 0.7) (thickness 0.15)) (justify left bottom))
    )
    (fp_text user "Author: Antmicro" (at -0.95 4.169 90) (layer "F.Fab") hide
        (effects (font (size 0.7 0.7) (thickness 0.15)) (justify left bottom))
    )
    (fp_rect (start -0.93 -0.47) (end 0.93 0.47)
      (stroke (width 0.05) (type solid)) (fill none) (layer "F.CrtYd"))
    (fp_rect (start -0.5 -0.25) (end 0.5 0.25)
      (stroke (width 0.15) (type solid)) (fill none) (layer "F.Fab"))
    (pad "1" smd roundrect (at -0.485 0 90) (size 0.59 0.64) (layers "F.Cu" "F.Paste" "F.Mask") (roundrect_rratio 0.25)
      (net 9 "GND") (pintype "passive"))
    (pad "2" smd roundrect (at 0.485 0 90) (size 0.59 0.64) (layers "F.Cu" "F.Paste" "F.Mask") (roundrect_rratio 0.25)
      (net 654 "Net-(U7-REF)") (pintype "passive"))
  )
	(footprint "data-center-rdimm-ddr4-tester-footprints:C_0402_1005Metric" (layer "F.Cu")
    (at 142.066328 115.237157)
    (descr "Capacitor SMD 0402")
    (tags "capacitor SMD 0402")
    (property "Author" "Antmicro")
    (property "Dielectric" "X5R")
    (property "License" "Apache-2.0")
    (property "MPN" "GRM155R61H104KE14D")
    (property "Manufacturer" "Murata")
    (property "Sheetfile" "interfaces.kicad_sch")
    (property "Sheetname" "Interfaces")
    (property "Val" "100n")
    (property "Voltage" "50V")
    (property "ki_description" " ")
    (attr smd)
    (fp_text reference "C184" (at -0.536328 3.922843) (layer "F.SilkS")
        (effects (font (size 0.7 0.7) (thickness 0.15)) (justify left bottom))
    )
    (fp_text value "C_100n_0402" (at 0 1.4) (layer "F.Fab") hide
        (effects (font (size 0.7 0.7) (thickness 0.15)) (justify left bottom))
    )
    (fp_text user "License: Apache-2.0" (at -0.932 5.17) (layer "F.Fab") hide
        (effects (font (size 0.7 0.7) (thickness 0.15)) (justify left bottom))
    )
    (fp_text user "Author: Antmicro" (at -0.932 4.17) (layer "F.Fab") hide
        (effects (font (size 0.7 0.7) (thickness 0.15)) (justify left bottom))
    )
    (fp_text user "${REFERENCE}" (at -0.932 3.168) (layer "F.Fab") hide
        (effects (font (size 0.7 0.7) (thickness 0.15)) (justify left bottom))
    )
    (fp_rect (start -0.94 -0.47) (end 0.94 0.47)
      (stroke (width 0.05) (type solid)) (fill none) (layer "F.CrtYd"))
    (fp_rect (start -0.499 -0.249) (end 0.499 0.249)
      (stroke (width 0.15) (type solid)) (fill none) (layer "F.Fab"))
    (pad "1" smd roundrect (at -0.484 0) (size 0.59 0.64) (layers "F.Cu" "F.Paste" "F.Mask") (roundrect_rratio 0.25)
      (net 75 "Net-(U7-V_{PLL})") (pintype "passive"))
    (pad "2" smd roundrect (at 0.484 0) (size 0.59 0.64) (layers "F.Cu" "F.Paste" "F.Mask") (roundrect_rratio 0.25)
      (net 9 "GND") (pintype "passive"))
  )
	(footprint "data-center-rdimm-ddr4-tester-footprints:C_0402_1005Metric" (layer "F.Cu")
    (at 142.066328 114.157157)
    (descr "Capacitor SMD 0402")
    (tags "capacitor SMD 0402")
    (property "Author" "Antmicro")
    (property "Dielectric" "")
    (property "License" "Apache-2.0")
    (property "MPN" "GRM155R61A475MEAAD")
    (property "Manufacturer" "Murata")
    (property "Sheetfile" "interfaces.kicad_sch")
    (property "Sheetname" "Interfaces")
    (property "Val" "4u7")
    (property "Voltage" "")
    (property "ki_description" " ")
    (attr smd)
    (fp_text reference "C187" (at -0.536328 3.922843) (layer "F.SilkS")
        (effects (font (size 0.7 0.7) (thickness 0.15)) (justify left bottom))
    )
    (fp_text value "C_4u7_0402" (at 0 1.4) (layer "F.Fab") hide
        (effects (font (size 0.7 0.7) (thickness 0.15)) (justify left bottom))
    )
    (fp_text user "License: Apache-2.0" (at -0.932 5.17) (layer "F.Fab") hide
        (effects (font (size 0.7 0.7) (thickness 0.15)) (justify left bottom))
    )
    (fp_text user "Author: Antmicro" (at -0.932 4.17) (layer "F.Fab") hide
        (effects (font (size 0.7 0.7) (thickness 0.15)) (justify left bottom))
    )
    (fp_text user "${REFERENCE}" (at -0.932 3.168) (layer "F.Fab") hide
        (effects (font (size 0.7 0.7) (thickness 0.15)) (justify left bottom))
    )
    (fp_rect (start -0.94 -0.47) (end 0.94 0.47)
      (stroke (width 0.05) (type solid)) (fill none) (layer "F.CrtYd"))
    (fp_rect (start -0.499 -0.249) (end 0.499 0.249)
      (stroke (width 0.15) (type solid)) (fill none) (layer "F.Fab"))
    (pad "1" smd roundrect (at -0.484 0) (size 0.59 0.64) (layers "F.Cu" "F.Paste" "F.Mask") (roundrect_rratio 0.25)
      (net 75 "Net-(U7-V_{PLL})") (pintype "passive"))
    (pad "2" smd roundrect (at 0.484 0) (size 0.59 0.64) (layers "F.Cu" "F.Paste" "F.Mask") (roundrect_rratio 0.25)
      (net 9 "GND") (pintype "passive"))
  )
)
